(kicad_pcb
	(version 20260206)
	(generator "pcbnew")
	(generator_version "10.0")
	(general
		(thickness 1.6)
		(legacy_teardrops no)
	)
	(paper "A4")
	(title_block
		(title "03242023_DA0F0TMBIJ0_F0T_Motherboard_J_brd_V01_OCP.brd")
		(comment 1 "Grand Teton / footprints 4304-4309 of 6105")
	)
	(layers
		(0 "F.Cu" signal "TOP")
		(4 "In1.Cu" signal "GND")
		(6 "In2.Cu" signal "IN1")
		(8 "In3.Cu" signal "GND1")
		(10 "In4.Cu" signal "IN2")
		(12 "In5.Cu" signal "GND2")
		(14 "In6.Cu" signal "IN3")
		(16 "In7.Cu" signal "GND3")
		(18 "In8.Cu" signal "VCC")
		(20 "In9.Cu" signal "VCC1")
		(22 "In10.Cu" signal "GND4")
		(24 "In11.Cu" signal "IN4")
		(26 "In12.Cu" signal "GND5")
		(28 "In13.Cu" signal "IN5")
		(30 "In14.Cu" signal "GND6")
		(32 "In15.Cu" signal "IN6")
		(34 "In16.Cu" signal "GND7")
		(2 "B.Cu" signal "BOTTOM")
		(9 "F.Adhes" user "F.Adhesive")
		(11 "B.Adhes" user "B.Adhesive")
		(13 "F.Paste" user "Package Geometry/Pastemask Top")
		(15 "B.Paste" user "Package Geometry/Pastemask Bottom")
		(5 "F.SilkS" user "Ref Des/Silkscreen Top")
		(7 "B.SilkS" user "Ref Des/Silkscreen Bottom")
		(1 "F.Mask" user "Board Geometry/Soldermask Top")
		(3 "B.Mask" user "Board Geometry/Soldermask Bottom")
		(17 "Dwgs.User" user "User.Drawings")
		(19 "Cmts.User" user "User.Comments")
		(21 "Eco1.User" user "User.Eco1")
		(23 "Eco2.User" user "User.Eco2")
		(25 "Edge.Cuts" user "Board Geometry/Outline")
		(27 "Margin" user)
		(31 "F.CrtYd" user "Package Geometry/Place Bound Top")
		(29 "B.CrtYd" user "Package Geometry/Place Bound Bottom")
		(35 "F.Fab" user "Ref Des/Assembly Top")
		(33 "B.Fab" user "Ref Des/Assembly Bottom")
	)
	(footprint ""
		(layer "B.Cu")
		(at 262.1026 -107.039918 -90)
		(property "Reference" "C1314"
			(at 0 0 90)
			(layer "B.SilkS")
			(hide yes)
			(effects
				(font
					(size 1.27 1.27)
				)
				(justify mirror)
			)
		)
		(property "Value" ""
			(at 0 0 90)
			(layer "B.Fab")
			(effects
				(font
					(size 1.27 1.27)
				)
				(justify mirror)
			)
		)
		(duplicate_pad_numbers_are_jumpers no)
		(fp_line
			(start -1.2954 0.5842)
			(end 1.2954 0.5842)
			(stroke
				(width 0.1524)
				(type default)
			)
			(layer "B.SilkS")
		)
		(fp_line
			(start 1.2954 0.5842)
			(end 1.2954 -0.5842)
			(stroke
				(width 0.1524)
				(type default)
			)
			(layer "B.SilkS")
		)
		(fp_line
			(start -1.2954 -0.5842)
			(end -1.2954 0.5842)
			(stroke
				(width 0.1524)
				(type default)
			)
			(layer "B.SilkS")
		)
		(fp_line
			(start 0 -0.5842)
			(end 0 0.5842)
			(stroke
				(width 0.1524)
				(type default)
			)
			(layer "B.SilkS")
		)
		(fp_line
			(start 1.2954 -0.5842)
			(end -1.2954 -0.5842)
			(stroke
				(width 0.1524)
				(type default)
			)
			(layer "B.SilkS")
		)
		(fp_line
			(start -0.8636 0.4572)
			(end 0.8636 0.4572)
			(stroke
				(width 0.1)
				(type default)
			)
			(layer "B.Fab")
		)
		(fp_line
			(start 0.8636 0.4572)
			(end 0.8636 0.4064)
			(stroke
				(width 0.1)
				(type default)
			)
			(layer "B.Fab")
		)
		(fp_line
			(start -1.1938 0.4064)
			(end -0.8636 0.4064)
			(stroke
				(width 0.1)
				(type default)
			)
			(layer "B.Fab")
		)
		(fp_line
			(start -0.8636 0.4064)
			(end -0.8636 0.4572)
			(stroke
				(width 0.1)
				(type default)
			)
			(layer "B.Fab")
		)
		(fp_line
			(start 0.8636 0.4064)
			(end 1.1938 0.4064)
			(stroke
				(width 0.1)
				(type default)
			)
			(layer "B.Fab")
		)
		(fp_line
			(start 1.1938 0.4064)
			(end 1.1938 -0.4064)
			(stroke
				(width 0.1)
				(type default)
			)
			(layer "B.Fab")
		)
		(fp_line
			(start -1.1938 -0.4064)
			(end -1.1938 0.4064)
			(stroke
				(width 0.1)
				(type default)
			)
			(layer "B.Fab")
		)
		(fp_line
			(start -0.8636 -0.4064)
			(end -1.1938 -0.4064)
			(stroke
				(width 0.1)
				(type default)
			)
			(layer "B.Fab")
		)
		(fp_line
			(start 0.8636 -0.4064)
			(end 0.8636 -0.4572)
			(stroke
				(width 0.1)
				(type default)
			)
			(layer "B.Fab")
		)
		(fp_line
			(start 1.1938 -0.4064)
			(end 0.8636 -0.4064)
			(stroke
				(width 0.1)
				(type default)
			)
			(layer "B.Fab")
		)
		(fp_line
			(start -0.8636 -0.4572)
			(end -0.8636 -0.4064)
			(stroke
				(width 0.1)
				(type default)
			)
			(layer "B.Fab")
		)
		(fp_line
			(start 0.8636 -0.4572)
			(end -0.8636 -0.4572)
			(stroke
				(width 0.1)
				(type default)
			)
			(layer "B.Fab")
		)
		(pad "1" smd rect
			(at 0.7366 0 180)
			(size 0.7112 0.8128)
			(layers "B.Cu" "B.Mask" "B.Paste")
			(net "P3V3_AUX_CLK_GEN_VDDPT_CK440")
		)
		(pad "2" smd rect
			(at -0.7366 0 180)
			(size 0.7112 0.8128)
			(layers "B.Cu" "B.Mask" "B.Paste")
			(net "GND")
		)
	)
	(footprint ""
		(layer "B.Cu")
		(at 426.00118 -354.903786 -90)
		(property "Reference" "PC1187"
			(at 0 0 90)
			(layer "B.SilkS")
			(hide yes)
			(effects
				(font
					(size 1.27 1.27)
				)
				(justify mirror)
			)
		)
		(property "Value" ""
			(at 0 0 90)
			(layer "B.Fab")
			(effects
				(font
					(size 1.27 1.27)
				)
				(justify mirror)
			)
		)
		(duplicate_pad_numbers_are_jumpers no)
		(fp_line
			(start -4.533392 2.249932)
			(end 4.533392 2.249932)
			(stroke
				(width 0.1524)
				(type default)
			)
			(layer "B.SilkS")
		)
		(fp_line
			(start 4.533392 2.249932)
			(end 4.533392 -2.249932)
			(stroke
				(width 0.1524)
				(type default)
			)
			(layer "B.SilkS")
		)
		(fp_line
			(start -4.533392 -2.249932)
			(end -4.533392 2.249932)
			(stroke
				(width 0.1524)
				(type default)
			)
			(layer "B.SilkS")
		)
		(fp_line
			(start 4.533392 -2.249932)
			(end -4.533392 -2.249932)
			(stroke
				(width 0.1524)
				(type default)
			)
			(layer "B.SilkS")
		)
		(fp_rect
			(start 5.39242 2.326132)
			(end 4.533392 -2.326132)
			(stroke
				(width 0)
				(type default)
			)
			(fill yes)
			(layer "B.SilkS")
		)
		(fp_line
			(start -3.750056 2.249932)
			(end 3.750056 2.249932)
			(stroke
				(width 0.1)
				(type default)
			)
			(layer "B.Fab")
		)
		(fp_line
			(start 3.750056 2.249932)
			(end 3.750056 -2.249932)
			(stroke
				(width 0.1)
				(type default)
			)
			(layer "B.Fab")
		)
		(fp_line
			(start -3.750056 -2.249932)
			(end -3.750056 2.249932)
			(stroke
				(width 0.1)
				(type default)
			)
			(layer "B.Fab")
		)
		(fp_line
			(start 3.750056 -2.249932)
			(end -3.750056 -2.249932)
			(stroke
				(width 0.1)
				(type default)
			)
			(layer "B.Fab")
		)
		(fp_text user "-"
			(at -4.659122 1.76911 270)
			(unlocked yes)
			(layer "B.SilkS")
			(effects
				(font
					(size 1.905 1.4224)
					(thickness 0.1524)
				)
				(justify left mirror)
			)
		)
		(fp_text user "+"
			(at 6.322314 0.786384 180)
			(unlocked yes)
			(layer "B.SilkS")
			(effects
				(font
					(size 1.905 1.4224)
					(thickness 0.1524)
				)
				(justify left mirror)
			)
		)
		(fp_text user "+"
			(at 6.322314 0.786384 180)
			(unlocked yes)
			(layer "B.Fab")
			(effects
				(font
					(size 1.905 1.4224)
					(thickness 0.1524)
				)
				(justify left mirror)
			)
		)
		(fp_text user "-"
			(at -4.8514 -0.14605 270)
			(unlocked yes)
			(layer "B.Fab")
			(effects
				(font
					(size 1.905 1.4224)
					(thickness 0.1524)
				)
				(justify left mirror)
			)
		)
		(pad "1" smd rect
			(at 3.199892 0 90)
			(size 2.413 2.8194)
			(layers "B.Cu" "B.Mask" "B.Paste")
			(net "PVCCFA_EHV_FIVRA_CPU0")
		)
		(pad "2" smd rect
			(at -3.199892 0 90)
			(size 2.413 2.8194)
			(layers "B.Cu" "B.Mask" "B.Paste")
			(net "GND")
		)
	)
	(footprint ""
		(layer "B.Cu")
		(at 66.107564 -243.345462 180)
		(property "Reference" "R158"
			(at 0 0 0)
			(layer "B.SilkS")
			(hide yes)
			(effects
				(font
					(size 1.27 1.27)
				)
				(justify mirror)
			)
		)
		(property "Value" ""
			(at 0 0 0)
			(layer "B.Fab")
			(effects
				(font
					(size 1.27 1.27)
				)
				(justify mirror)
			)
		)
		(duplicate_pad_numbers_are_jumpers no)
		(fp_line
			(start 0.7874 0.4064)
			(end 0.7874 -0.4064)
			(stroke
				(width 0.1524)
				(type default)
			)
			(layer "B.SilkS")
		)
		(fp_line
			(start 0.7874 -0.4064)
			(end -0.7874 -0.4064)
			(stroke
				(width 0.1524)
				(type default)
			)
			(layer "B.SilkS")
		)
		(fp_line
			(start -0.7874 0.4064)
			(end 0.7874 0.4064)
			(stroke
				(width 0.1524)
				(type default)
			)
			(layer "B.SilkS")
		)
		(fp_line
			(start -0.7874 -0.4064)
			(end -0.7874 0.4064)
			(stroke
				(width 0.1524)
				(type default)
			)
			(layer "B.SilkS")
		)
		(fp_line
			(start 0.67945 0.3048)
			(end 0.67945 -0.305054)
			(stroke
				(width 0.1)
				(type default)
			)
			(layer "B.Fab")
		)
		(fp_line
			(start 0.67945 -0.305054)
			(end 0.12065 -0.305054)
			(stroke
				(width 0.1)
				(type default)
			)
			(layer "B.Fab")
		)
		(fp_line
			(start 0.12065 0.3048)
			(end 0.67945 0.3048)
			(stroke
				(width 0.1)
				(type default)
			)
			(layer "B.Fab")
		)
		(fp_line
			(start 0.12065 0.2794)
			(end 0.12065 0.3048)
			(stroke
				(width 0.1)
				(type default)
			)
			(layer "B.Fab")
		)
		(fp_line
			(start 0.12065 -0.2794)
			(end -0.12065 -0.2794)
			(stroke
				(width 0.1)
				(type default)
			)
			(layer "B.Fab")
		)
		(fp_line
			(start 0.12065 -0.305054)
			(end 0.12065 -0.2794)
			(stroke
				(width 0.1)
				(type default)
			)
			(layer "B.Fab")
		)
		(fp_line
			(start -0.120396 0.3048)
			(end -0.120396 0.2794)
			(stroke
				(width 0.1)
				(type default)
			)
			(layer "B.Fab")
		)
		(fp_line
			(start -0.120396 0.2794)
			(end 0.12065 0.2794)
			(stroke
				(width 0.1)
				(type default)
			)
			(layer "B.Fab")
		)
		(fp_line
			(start -0.12065 -0.2794)
			(end -0.12065 -0.3048)
			(stroke
				(width 0.1)
				(type default)
			)
			(layer "B.Fab")
		)
		(fp_line
			(start -0.12065 -0.3048)
			(end -0.67945 -0.3048)
			(stroke
				(width 0.1)
				(type default)
			)
			(layer "B.Fab")
		)
		(fp_line
			(start -0.67945 0.3048)
			(end -0.120396 0.3048)
			(stroke
				(width 0.1)
				(type default)
			)
			(layer "B.Fab")
		)
		(fp_line
			(start -0.67945 -0.3048)
			(end -0.67945 0.3048)
			(stroke
				(width 0.1)
				(type default)
			)
			(layer "B.Fab")
		)
		(pad "1" smd circle
			(at 0.40005 0)
			(size 0 0)
			(layers "B.Cu" "B.Mask" "B.Paste")
			(net "RST_CPU1_BUF_R_N")
		)
		(pad "2" smd circle
			(at -0.40005 0)
			(size 0 0)
			(layers "B.Cu" "B.Mask" "B.Paste")
			(net "RST_CPU1_LVC1_N")
		)
	)
	(footprint ""
		(layer "B.Cu")
		(at 120.858534 -324.792086 -90)
		(property "Reference" "PC541_P1_4"
			(at 0 0 90)
			(layer "B.SilkS")
			(hide yes)
			(effects
				(font
					(size 1.27 1.27)
				)
				(justify mirror)
			)
		)
		(property "Value" ""
			(at 0 0 90)
			(layer "B.Fab")
			(effects
				(font
					(size 1.27 1.27)
				)
				(justify mirror)
			)
		)
		(duplicate_pad_numbers_are_jumpers no)
		(fp_line
			(start -1.524 0.762)
			(end 1.524 0.762)
			(stroke
				(width 0.1524)
				(type default)
			)
			(layer "B.SilkS")
		)
		(fp_line
			(start 1.524 0.762)
			(end 1.524 -0.762)
			(stroke
				(width 0.1524)
				(type default)
			)
			(layer "B.SilkS")
		)
		(fp_line
			(start -1.524 -0.762)
			(end -1.524 0.762)
			(stroke
				(width 0.1524)
				(type default)
			)
			(layer "B.SilkS")
		)
		(fp_line
			(start 1.524 -0.762)
			(end -1.524 -0.762)
			(stroke
				(width 0.1524)
				(type default)
			)
			(layer "B.SilkS")
		)
		(fp_line
			(start -1.1049 0.724916)
			(end -1.1049 -0.724916)
			(stroke
				(width 0.1)
				(type default)
			)
			(layer "B.Fab")
		)
		(fp_line
			(start 1.1049 0.724916)
			(end -1.1049 0.724916)
			(stroke
				(width 0.1)
				(type default)
			)
			(layer "B.Fab")
		)
		(fp_line
			(start -1.1049 -0.724916)
			(end 1.1049 -0.724916)
			(stroke
				(width 0.1)
				(type default)
			)
			(layer "B.Fab")
		)
		(fp_line
			(start 1.1049 -0.724916)
			(end 1.1049 0.724916)
			(stroke
				(width 0.1)
				(type default)
			)
			(layer "B.Fab")
		)
		(pad "1" smd rect
			(at 0.889 0 270)
			(size 1.016 1.27)
			(layers "B.Cu" "B.Mask" "B.Paste")
			(net "PVCCIN_CPU1")
		)
		(pad "2" smd rect
			(at -0.889 0 270)
			(size 1.016 1.27)
			(layers "B.Cu" "B.Mask" "B.Paste")
			(net "GND")
		)
	)
	(footprint ""
		(layer "B.Cu")
		(at 177.355754 -110.975394 -90)
		(property "Reference" "C1904"
			(at 0 0 90)
			(layer "B.SilkS")
			(hide yes)
			(effects
				(font
					(size 1.27 1.27)
				)
				(justify mirror)
			)
		)
		(property "Value" ""
			(at 0 0 90)
			(layer "B.Fab")
			(effects
				(font
					(size 1.27 1.27)
				)
				(justify mirror)
			)
		)
		(duplicate_pad_numbers_are_jumpers no)
		(fp_line
			(start -0.69215 0.2921)
			(end 0.69215 0.2921)
			(stroke
				(width 0.1524)
				(type default)
			)
			(layer "B.SilkS")
		)
		(fp_line
			(start 0.69215 0.2921)
			(end 0.69215 -0.2921)
			(stroke
				(width 0.1524)
				(type default)
			)
			(layer "B.SilkS")
		)
		(fp_line
			(start -0.69215 -0.2921)
			(end -0.69215 0.2921)
			(stroke
				(width 0.1524)
				(type default)
			)
			(layer "B.SilkS")
		)
		(fp_line
			(start 0.69215 -0.2921)
			(end -0.69215 -0.2921)
			(stroke
				(width 0.1524)
				(type default)
			)
			(layer "B.SilkS")
		)
		(fp_line
			(start -0.51435 0.2794)
			(end 0.51435 0.2794)
			(stroke
				(width 0.1)
				(type default)
			)
			(layer "B.Fab")
		)
		(fp_line
			(start 0.51435 0.2794)
			(end 0.51435 -0.2794)
			(stroke
				(width 0.1)
				(type default)
			)
			(layer "B.Fab")
		)
		(fp_line
			(start -0.51435 -0.2794)
			(end -0.51435 0.2794)
			(stroke
				(width 0.1)
				(type default)
			)
			(layer "B.Fab")
		)
		(fp_line
			(start 0.51435 -0.2794)
			(end -0.51435 -0.2794)
			(stroke
				(width 0.1)
				(type default)
			)
			(layer "B.Fab")
		)
		(pad "1" smd circle
			(at 0.40005 0 90)
			(size 0 0)
			(layers "B.Cu" "B.Mask" "B.Paste")
			(net "P3V3_AUX_FPGA_VCCIO5")
		)
		(pad "2" smd circle
			(at -0.40005 0 90)
			(size 0 0)
			(layers "B.Cu" "B.Mask" "B.Paste")
			(net "GND")
		)
		(zone
			(layer "B.Cu")
			(hatch none 0.5)
			(connect_pads
				(clearance 0)
			)
			(min_thickness 0.25)
			(keepout
				(tracks not_allowed)
				(vias allowed)
				(pads allowed)
				(copperpour not_allowed)
				(footprints allowed)
			)
			(placement
				(enabled no)
				(sheetname "")
			)
			(fill
				(thermal_gap 0.5)
				(thermal_bridge_width 0.5)
				(island_removal_mode 0)
			)
			(polygon
				(pts
					(xy 177.268124 -110.784894) (xy 177.209958 -110.876334) (xy 177.209958 -111.075724) (xy 177.268124 -111.165894)
					(xy 177.443384 -111.165894) (xy 177.501804 -111.075724) (xy 177.501804 -110.876334) (xy 177.443638 -110.784894)
				)
			)
		)
	)
	(footprint ""
		(layer "B.Cu")
		(at 298.47413 -400.999452 -90)
		(property "Reference" "PR2520"
			(at 0 0 90)
			(layer "B.SilkS")
			(hide yes)
			(effects
				(font
					(size 1.27 1.27)
				)
				(justify mirror)
			)
		)
		(property "Value" ""
			(at 0 0 90)
			(layer "B.Fab")
			(effects
				(font
					(size 1.27 1.27)
				)
				(justify mirror)
			)
		)
		(duplicate_pad_numbers_are_jumpers no)
		(fp_line
			(start -0.7874 0.4064)
			(end 0.7874 0.4064)
			(stroke
				(width 0.1524)
				(type default)
			)
			(layer "B.SilkS")
		)
		(fp_line
			(start 0.7874 0.4064)
			(end 0.7874 -0.4064)
			(stroke
				(width 0.1524)
				(type default)
			)
			(layer "B.SilkS")
		)
		(fp_line
			(start -0.7874 -0.4064)
			(end -0.7874 0.4064)
			(stroke
				(width 0.1524)
				(type default)
			)
			(layer "B.SilkS")
		)
		(fp_line
			(start 0.7874 -0.4064)
			(end -0.7874 -0.4064)
			(stroke
				(width 0.1524)
				(type default)
			)
			(layer "B.SilkS")
		)
		(fp_line
			(start -0.67945 0.3048)
			(end -0.120396 0.3048)
			(stroke
				(width 0.1)
				(type default)
			)
			(layer "B.Fab")
		)
		(fp_line
			(start -0.120396 0.3048)
			(end -0.120396 0.2794)
			(stroke
				(width 0.1)
				(type default)
			)
			(layer "B.Fab")
		)
		(fp_line
			(start 0.12065 0.3048)
			(end 0.67945 0.3048)
			(stroke
				(width 0.1)
				(type default)
			)
			(layer "B.Fab")
		)
		(fp_line
			(start 0.67945 0.3048)
			(end 0.67945 -0.305054)
			(stroke
				(width 0.1)
				(type default)
			)
			(layer "B.Fab")
		)
		(fp_line
			(start -0.120396 0.2794)
			(end 0.12065 0.2794)
			(stroke
				(width 0.1)
				(type default)
			)
			(layer "B.Fab")
		)
		(fp_line
			(start 0.12065 0.2794)
			(end 0.12065 0.3048)
			(stroke
				(width 0.1)
				(type default)
			)
			(layer "B.Fab")
		)
		(fp_line
			(start -0.12065 -0.2794)
			(end -0.12065 -0.3048)
			(stroke
				(width 0.1)
				(type default)
			)
			(layer "B.Fab")
		)
		(fp_line
			(start 0.12065 -0.2794)
			(end -0.12065 -0.2794)
			(stroke
				(width 0.1)
				(type default)
			)
			(layer "B.Fab")
		)
		(fp_line
			(start -0.67945 -0.3048)
			(end -0.67945 0.3048)
			(stroke
				(width 0.1)
				(type default)
			)
			(layer "B.Fab")
		)
		(fp_line
			(start -0.12065 -0.3048)
			(end -0.67945 -0.3048)
			(stroke
				(width 0.1)
				(type default)
			)
			(layer "B.Fab")
		)
		(fp_line
			(start 0.12065 -0.305054)
			(end 0.12065 -0.2794)
			(stroke
				(width 0.1)
				(type default)
			)
			(layer "B.Fab")
		)
		(fp_line
			(start 0.67945 -0.305054)
			(end 0.12065 -0.305054)
			(stroke
				(width 0.1)
				(type default)
			)
			(layer "B.Fab")
		)
		(pad "1" smd circle
			(at 0.40005 0 90)
			(size 0 0)
			(layers "B.Cu" "B.Mask" "B.Paste")
			(net "P12V_HSC_SENSE2_P")
		)
		(pad "2" smd circle
			(at -0.40005 0 90)
			(size 0 0)
			(layers "B.Cu" "B.Mask" "B.Paste")
			(net "P12V_HSC_SENSE2_R1_P")
		)
	)
)
